# GT_Fan BP_MPS_Pilot_BOM_20230421.xlsx — BOM Sharing Template (bom)
|  | Full Manufacturer Name | Complete Manufacturing Part Number |  |  |  |
| Part Description | Manufacturer | Manufacturing Part Number | Quantity | Location (CRD) | HSC/VR |
| CAP CHIP 0.1U 16V(10%.X7R.0402) | MUR | WBM155R71C104K | 41 | C51,C53,C93,C1932,C1933,C1938,C1939,C1941,C2094,C2095,C55,C57,C100,C165,C172,C188,C1943,C1945,C1953,C2060,C2061,C2062,C2063,C2064,C2065,C2066,C2067,C2068,C2069,C2070,C2071,C2072,C2073,C2084,C2087,C2088,C2089,C2090,C2091,C2092,C2093 |  |
| CAP CHIP 100NF 50V(+-10%,X7R,0402) | YGO | CC0402KRX7R9BB104 | 8 | C52,C54,C56,C58,C1940,C1942,C1946,C1948 |  |
| CAP CHIP 0.1U 25V(+-10%,X7R,0402) | YGO | CC0402KRX7R8BB104 | 18 | PC5,PC20,PC27,PC33,PC40,PC46,PC52,PC58,C1502,C2010,PC3118,PC3119,PC3120,PC3121,PC3122,PC3123,PC3124,PC3125 |  |
| CAP CHIP 220P 50V(+-10%.X7R.0402) | RHT | CC0402X221K3OST-S | 32 | C2014,C2015,C2016,C2017,C2020,C2021,C2022,C2023,C2028,C2029,C2030,C2031,C2032,C2033,C2034,C2035,C2040,C2041,C2042,C2043,C2044,C2045,C2046,C2047,C2052,C2053,C2054,C2055,C2056,C2057,C2058,C2059 |  |
| CAP CHIP 0.015U 16V(+-10%.X7R.0402) | MUR | GRM155R71C153K | 1 | C2080 |  |
| CAP CHIP 0.033U 16V(+-10%.X7R.0402) | RHT | CC0402X333K1OST-S | 1 | C2081 |  |
| CAP CHIP 0.056U 16V(+-10%,X7R,0402) | MUR | GRM155R71C563K | 1 | C2082 |  |
| CAP CHIP 0.082U,16V(+-10%,X7R,0402) | MUR | GRM155R71C823K | 1 | C2083 |  |
| CAP CHIP 0.22U 16V(10%.X7R.0402) | MUR | GRM155R71C224K | 1 | C2085 |  |
| CAP CHIP 0.47UF 10V(+-10%,X7R,0402) | YGO | CC0402KRX7R6BB474 | 1 | C2086 |  |
| CAP CHIP 2.2UF 100V(+-10%,X7R,1206) | MUR | GRM31CR72A225K | 24 | C2096,C2097,C2098,C2099,C2100,C2101,C2102,C2103,C2104,C2105,C2106,C2107,C2108,C2109,C2110,C2111,C2112,C2113,C2114,C2115,C2116,C2117,C2118,C2119 |  |
| DIODE SMD SDMK0340L-7-F(40V.30MA) | DDS | SDMK0340L-7-F | 16 | D113,D114,D131,D132,D133,D134,D135,D136,D137,D138,D139,D140,D141,D142,D143,D144 |  |
| CONN DIP HEADER 16P 2R MS(P2,H10.36) | BWE | 70127-16C5 | 8 | J1,J2,J3,J4,J5,J6,J7,J8 |  |
| CAP CHIP 0.47U 100V(+-10%.X7R.0805) | MUR | GRM21BR72A474K | 16 | PC1,PC8,PC9,PC16,PC24,PC30,PC36,PC37,PC43,PC49,PC55,PC60,PC61,PC62,PC63,PC64 |  |
| CAP CHIP 2.2UF 10V(+-10%,X6S,0402) | MUR | GRM155C81A225K | 16 | PC3,PC4,PC18,PC19,PC25,PC26,PC31,PC32,PC38,PC39,PC44,PC45,PC50,PC51,PC56,PC57 |  |
| CAP CHIP 0.01U 50V(+-10%,X7R,0402) | MUR | WBM155R71H103K | 8 | PC6,PC21,PC28,PC34,PC41,PC47,PC53,PC59 |  |
| CAP ELEC SMD 56UF 80V(20%,ESR33,10*10) | NPN | HHXD800ARA560MJA0G | 8 | PC7,PC22,PC23,PC29,PC35,PC42,PC48,PC54 |  |
| CAP CHIP 1000P 50V(+-5%.X7R.0402) | API | C1005X7R102JGT | 8 | PC2118,PC2119,PC2120,PC2121,PC2122,PC2123,PC2124,PC2125 |  |
| DIODE SMD B380-13-F(80V,100A,SCHOTTKY) | DDS | B380-13-F | 8 | PD1,PD7,PD8,PD9,PD10,PD11,PD12,PD13 |  |
| DIODE TVS 5.0SMDJ54A(54V,57.5A,5000W) | LFI | 5.0SMDJ54A | 8 | PD3,PD4,PD6,PD14,PD15,PD16,PD17,PD18 |  |
| RES CHIP 0 1/16W +-5%(0402)EF | WTC | WR04X000PTR | 49 | PR1,PR21,PR27,PR35,PR47,PR55,PR63,PR71,R313,R314,R503,R506,R513,R4959,R4968,R4969,R5094,R5095,R5096,R5097,R5098,R5099,R5100,R5101,R5102,R5103,R5104,R5105,R5107,R5108,R5110,R5111,R5353,R5354,R5355,R5356,R5416,R5417,R5418,R5419,R5420,R5421,R5422,R5423,R5424,R5425,R5645,R5679,R5680 |  |
| RES CHIP 100K 1/16W +-1%(0402)EF | WTC | WR04X1003FTR | 49 | PR3,PR22,PR28,PR36,PR48,PR56,PR64,PR72,R572,R5525,R5526,R5527,R5528,R5529,R5530,R5531,R5532,R5533,R5534,R5535,R5536,R5537,R5538,R5539,R5540,PR5,PR24,PR29,PR37,PR49,PR57,PR65,PR73,R5302,R5303,R5306,R5307,R5310,R5311,R5314,R5315,R5318,R5319,R5322,R5323,R5326,R5327,R5330,R5331 |  |
| RES CHIP 8.25K 1/16W +-0.1%(0402)EF | WTC | WF04H8251BTR | 16 | PR6,PR10,PR26,PR30,PR34,PR38,PR42,PR46,PR50,PR54,PR66,PR70,PR74,PR78,PR58,PR62 |  |
| RES CHIP 10K 1/16W +-1%(0402)EF | WTC | WR04X1002FTR | 40 | PR8,PR32,PR40,PR44,PR52,PR60,PR68,PR76,R5093,R5681,R5682,R98,R99,R4852,R4856,R4990,R4992,R5362,R5363,R5370,R5371,R5378,R5379,R5384,R5387,R5389,R5391,R5393,R5395,R5397,R5399,R101,R102,R309,R519,R521,R4860,R4864,R4965,R4967 |  |
| RES CHIP 100K 1/10W +-5%(0603) | WTC | WR06X104JTL | 16 | R5300,R5301,R5304,R5305,R5308,R5309,R5312,R5313,R5316,R5317,R5320,R5321,R5324,R5325,R5328,R5329 |  |
| RES CHIP 49.9K 1/16W +-1%(0402)EF | YGO | RC0402FR-0749K9P | 8 | PR9,PR33,PR41,PR45,PR53,PR61,PR69,PR77 |  |
| IC OTHER(30P)MP5048GU-Z (QFN) | MPS | MP5048GU-Z | 8 | PU1,PU3,PU4,PU5,PU6,PU7,PU8,PU9 |  |
| TRANS MOSFET FDN352AP(-30V,-1.3A) | FAC | FDN352AP | 8 | Q9,Q10,Q11,Q12,Q13,Q14,Q15,Q16 |  |
| RES CHIP 33 1/16W +-1%(0402)EF | WTC | WR04X33R0FTR | 52 | R5128,R5130,R5131,R5132,R5184,R5186,R5187,R5188,R5196,R5198,R5200,R5201,R5202,R5203,R5204,R5205,R5216,R5218,R5220,R5221,R5222,R5223,R5224,R5225,R5236,R5238,R5240,R5241,R5242,R5243,R5244,R5245,R5487,R5488,R5489,R5490,R5491,R5492,R5493,R5494,R5458,R5459,R5460,R5461,R5466,R5467,R5468,R5469,R5557,R5558,R5568,R5569 |  |
| RES CHIP 240 1/16W +-1%(0402)EF | WTC | WR04X2400FTR | 8 | R100,R103,R104,R105,R4855,R4859,R4863,R4867 |  |
| RES CHIP 4.7K 1/16W +-5%(0402)EF | WTC | WR04X472 JTR | 58 | R310,R311,R4848,R4849,R5269,R5270,R5271,R5272,R5273,R5274,R5275,R5276,R5277,R5278,R5279,R5280,R5281,R5282,R5283,R5288,R5559,R5566,R5648,R5649,R5652,R5653,R5658,R5659,R5660,R5661,R336,R344,R352,R360,R5470,R5471,R5486,R5503,R5504,R5505,R5506,R5507,R5508,R5509,R5510,R5519,R5520,R5521,R5522,R5524,R5647,R5651,R5656,R5657,R5666,R5667,R5668,R5669 |  |
| RES CHIP 1.2K 1/16W+-1%(0402)EF | WTC | WR04X1201FTR | 16 | R5689,R5690,R5691,R5692,R5693,R5694,R5695,R5696,R5697,R5698,R5699,R5700,R5701,R5702,R5703,R5704 |  |
| RES CHIP 220 1/16W +-5%(0402)EF | WTC | WR04X221 JTR | 15 | R317,R4781,R4782,R4935,R4939,R4941,R4943,R4947,R4948,R4949,R4950,R5563,R5564,R5570,R5572 |  |
| RES CHIP 1K 1/16W +-1%(0402)EF | WTC | WR04X1001FTR | 20 | R509,R510,R511,R512,R2355,R2362,R4955,R4956,R4957,R4958,R5115,R5117,R5674,R5675,R2360,R5113,R5673,R5684,R5685,R5686 |  |
| RES CHIP 200 1/16W +-1%(0402)EF | WTC | WR04X2000FTR | 1 | R4970 |  |
| RES CHIP 2.4K 1/16W+-1%(0402)EF | YGO | RC0402FR-072K4P | 16 | R5349,R5358,R5364,R5366,R5372,R5374,R5380,R5382,R5400,R5402,R5404,R5406,R5408,R5410,R5412,R5414 |  |
| RES CHIP 12K 1/16W +-1%(0402)EF | WTC | WR04X1202FTR | 16 | R5426,R5427,R5428,R5429,R5430,R5431,R5432,R5433,R5434,R5435,R5436,R5437,R5438,R5439,R5440,R5441 |  |
| RES CHIP 100 1/16W +-1%(0402)EF | WTC | WR04X1000FTR | 8 | R5495,R5496,R5497,R5498,R5499,R5500,R5501,R5502 |  |
| IC(24P) PCA9555PW(TSSOP)EP | PHI | PCA9555PW | 1 | U7 |  |
| IC(24P)PCA9552PW(TSSOP) | PHI | PCA9552PW | 1 | U8 |  |
| IC(6P) 74LVC2G17GW (SC-88) | PHI | 74LVC2G17GW | 4 | U23,U24,U25,U26 |  |
| IC EEPROM(8P) M24256-BRMN6TP(SO8) | SGT | M24256-BRMN6TP | 1 | U59 |  |
| IC OTHER(5P)TC7SZ07FU(SSOP5) | TOS | TC7SZ07FU | 8 | U60,U62,U64,U66,U399,U400,U401,U402 |  |
| DIODE SMD BAT54CW-7-F(30V 0.2A SCHOTTKY) | DDS | BAT54CW-7-F | 8 | U61,U63,U65,U67,U323,U325,U327,U329 |  |
| IC(5P) 74LVC1G08GW (SC70-5) | PHI | 74LVC1G08GW | 8 | U74,U359,U361,U377,U379,U381,U383,U385 |  |
| TRANMOS 2N7002KW SOT323(60V, 115MA,0.2W) | PJT | 2N7002KW | 24 | U340,U342,U362,U363,U364,U365,U366,U367,U368,U369,U370,U371,U372,U373,U374,U375,U405,U406,U407,U408,U409,U410,U411,U412 |  |
| IC(14P) 74LVC07APW(TSSOP) | PHI | 74LVC07APW | 2 | U389,U390 |  |
| IC(5P) 74LVC1G14GW (SC-88A) | PHI | 74LVC1G14GW | 8 | U391,U392,U393,U394,U395,U396,U397,U398 |  |
| HOLE_C10-16D6-4B10_OB22XC5B_NPB | FVT | FBF0D01001 | 1 | H11 |  |
| IC CTRL(28P)MAX31790ATI+T(TQFN) | MAX | MAX31790ATI+T | 2 | U317,U330 |  |
| RES CHIP 0 1/16W +-5%(0402)EF | WTC | WR04X000PTR | 16 | R5598,R5599,R5600,R5602,R5604,R5605,R5606,R5608,R5610,R5611,R5612,R5614,R5616,R5617,R5618,R5620 |  |
| RES CHIP 100 1/16W +-1%(0402)EF | WTC | WR04X1000FTR | 8 | R5597,R5601,R5603,R5607,R5609,R5613,R5615,R5619 |  |
